# Lightning  FCB_Stackup.xlsx — Wiwynn (pcb-stackup)
|  |  |  |  |  |  |  |  |  | Single Ended Type(mil) |  |
|  |  |  |  |  |  |  |  | Imp | 50 |  |
|  |  |  |  |  |  |  |  | Variation | Outer ±5Ω |  |
|  |  |  |  |  |  |  |  | Bus | MISC. |  |
|  |  |  |  |  |  |  |  | Type | SE |  |
| Layer |  |  | Thickness |  | Er |  | Df(1G) | Layers | 1,4 |  |
|  |  | Cu oz | Wiwynn | Vender | Wiwynn | Vender |  |  | Wiwynn | Vender |
|  | Mask |  | 0.5 |  | 4.2 |  |  |  | Width | Width |
| Top | Signal | 0.5 oz + plating | 1.7 |  |  |  |  | S1 | 5.5 |  |
|  | Prepreg |  | 3.5 |  | 3.7 |  |  |  |  |  |
| L2 | PWR/GND | 2 oz | 2.6 |  |  |  |  | G2 |  |  |
|  | Core |  | 47 |  | 4.2 |  |  |  |  |  |
| L3 | GND/PWR | 2 oz | 2.6 |  |  |  |  | P3 |  |  |
|  | Prepreg |  | 3.5 |  | 3.7 |  |  |  |  |  |
| Bottom | Signal | 0.5 oz + plating | 1.7 |  |  |  |  | S4 | 5.5 |  |
|  | Mask |  | 0.5 |  | 4.2 |  |  |  |  |  |
| Thickness requirement: 1.6±10% mm |  | mil | 63.6 |  |  |  |  |  |  |  |
|  |  | mm | 1.6154432308864619 |  |  |  |  |  |  |  |
| Note: | 1. Unit is mil |  |  |  |  |  |  |  |  |  |
|  | 2. The total thickness includes trace and solder mask |  |  |  |  |  |  |  |  |  |
|  | 3. Minimum via hole copper thickness is 1.0 mil |  |  |  |  |  |  |  |  |  |
|  | 4. Minimum surface copper thickness 1.5 mil |  |  |  |  |  |  |  |  |  |
